(kicad_pcb
	(version 20260206)
	(generator "pcbnew")
	(generator_version "10.0")
	(general
		(thickness 1.6)
		(legacy_teardrops no)
	)
	(paper "A4")
	(title_block
		(title "04192023_DAF0TMB3IC0_F0TG_MB_C_brd_V02_OCP.brd")
		(comment 1 "Grand Teton / footprint 4612 of 8354 (J32), pads 114-226 of 291")
	)
	(layers
		(0 "F.Cu" signal "TOP")
		(4 "In1.Cu" signal "GND")
		(6 "In2.Cu" signal "IN1")
		(8 "In3.Cu" signal "GND1")
		(10 "In4.Cu" signal "IN2")
		(12 "In5.Cu" signal "GND2")
		(14 "In6.Cu" signal "IN3")
		(16 "In7.Cu" signal "GND3")
		(18 "In8.Cu" signal "VCC")
		(20 "In9.Cu" signal "VCC1")
		(22 "In10.Cu" signal "GND4")
		(24 "In11.Cu" signal "IN4")
		(26 "In12.Cu" signal "GND5")
		(28 "In13.Cu" signal "IN5")
		(30 "In14.Cu" signal "GND6")
		(32 "In15.Cu" signal "IN6")
		(34 "In16.Cu" signal "GND7")
		(2 "B.Cu" signal "BOTTOM")
		(9 "F.Adhes" user "F.Adhesive")
		(11 "B.Adhes" user "B.Adhesive")
		(13 "F.Paste" user "Package Geometry/Pastemask Top")
		(15 "B.Paste" user "Package Geometry/Pastemask Bottom")
		(5 "F.SilkS" user "Ref Des/Silkscreen Top")
		(7 "B.SilkS" user "Ref Des/Silkscreen Bottom")
		(1 "F.Mask" user "Board Geometry/Soldermask Top")
		(3 "B.Mask" user "Board Geometry/Soldermask Bottom")
		(17 "Dwgs.User" user "User.Drawings")
		(19 "Cmts.User" user "User.Comments")
		(21 "Eco1.User" user "User.Eco1")
		(23 "Eco2.User" user "User.Eco2")
		(25 "Edge.Cuts" user "Board Geometry/Outline")
		(27 "Margin" user)
		(31 "F.CrtYd" user "Package Geometry/Place Bound Top")
		(29 "B.CrtYd" user "Package Geometry/Place Bound Bottom")
		(35 "F.Fab" user "Ref Des/Assembly Top")
		(33 "B.Fab" user "Ref Des/Assembly Bottom")
	)
	(footprint ""
		(layer "F.Cu")
		(at 27.20213 -255.560322 180)
		(property "Reference" "J32"
			(at 1.80086 -81.974436 0)
			(unlocked yes)
			(layer "F.SilkS")
			(effects
				(font
					(size 0.7874 0.5842)
					(thickness 0.1524)
				)
			)
		)
		(property "Value" ""
			(at 0 0 180)
			(layer "F.Fab")
			(effects
				(font
					(size 1.27 1.27)
				)
			)
		)
		(duplicate_pad_numbers_are_jumpers no)
		(pad "114" smd rect
			(at -2.050034 37.824918 90)
			(size 0.519938 1.4986)
			(layers "F.Cu" "F.Mask" "F.Paste")
			(net "GND")
		)
		(pad "115" smd rect
			(at -2.050034 38.675056 90)
			(size 0.519938 1.4986)
			(layers "F.Cu" "F.Mask" "F.Paste")
			(net "M_E_CPU1_SB_DQS_DP<1>")
		)
		(pad "116" smd rect
			(at -2.050034 39.52494 90)
			(size 0.519938 1.4986)
			(layers "F.Cu" "F.Mask" "F.Paste")
			(net "M_E_CPU1_SB_DQS_DN<1>")
		)
		(pad "117" smd rect
			(at -2.050034 40.375078 90)
			(size 0.519938 1.4986)
			(layers "F.Cu" "F.Mask" "F.Paste")
			(net "GND")
		)
		(pad "118" smd rect
			(at -2.050034 41.224962 90)
			(size 0.519938 1.4986)
			(layers "F.Cu" "F.Mask" "F.Paste")
			(net "M_E_CPU1_SB_DQ<12>")
		)
		(pad "119" smd rect
			(at -2.050034 42.0751 90)
			(size 0.519938 1.4986)
			(layers "F.Cu" "F.Mask" "F.Paste")
			(net "GND")
		)
		(pad "120" smd rect
			(at -2.050034 42.924984 90)
			(size 0.519938 1.4986)
			(layers "F.Cu" "F.Mask" "F.Paste")
			(net "M_E_CPU1_SB_DQ<13>")
		)
		(pad "121" smd rect
			(at -2.050034 43.775122 90)
			(size 0.519938 1.4986)
			(layers "F.Cu" "F.Mask" "F.Paste")
			(net "GND")
		)
		(pad "122" smd rect
			(at -2.050034 44.625006 90)
			(size 0.519938 1.4986)
			(layers "F.Cu" "F.Mask" "F.Paste")
			(net "M_E_CPU1_SB_DQ<16>")
		)
		(pad "123" smd rect
			(at -2.050034 45.47489 90)
			(size 0.519938 1.4986)
			(layers "F.Cu" "F.Mask" "F.Paste")
			(net "GND")
		)
		(pad "124" smd rect
			(at -2.050034 46.325028 90)
			(size 0.519938 1.4986)
			(layers "F.Cu" "F.Mask" "F.Paste")
			(net "M_E_CPU1_SB_DQ<17>")
		)
		(pad "125" smd rect
			(at -2.050034 47.174912 90)
			(size 0.519938 1.4986)
			(layers "F.Cu" "F.Mask" "F.Paste")
			(net "GND")
		)
		(pad "126" smd rect
			(at -2.050034 48.02505 90)
			(size 0.519938 1.4986)
			(layers "F.Cu" "F.Mask" "F.Paste")
			(net "M_E_CPU1_SB_DQS_DP<2>")
		)
		(pad "127" smd rect
			(at -2.050034 48.874934 90)
			(size 0.519938 1.4986)
			(layers "F.Cu" "F.Mask" "F.Paste")
			(net "M_E_CPU1_SB_DQS_DN<2>")
		)
		(pad "128" smd rect
			(at -2.050034 49.725072 90)
			(size 0.519938 1.4986)
			(layers "F.Cu" "F.Mask" "F.Paste")
			(net "GND")
		)
		(pad "129" smd rect
			(at -2.050034 50.574956 90)
			(size 0.519938 1.4986)
			(layers "F.Cu" "F.Mask" "F.Paste")
			(net "M_E_CPU1_SB_DQ<20>")
		)
		(pad "130" smd rect
			(at -2.050034 51.425094 90)
			(size 0.519938 1.4986)
			(layers "F.Cu" "F.Mask" "F.Paste")
			(net "GND")
		)
		(pad "131" smd rect
			(at -2.050034 52.274978 90)
			(size 0.519938 1.4986)
			(layers "F.Cu" "F.Mask" "F.Paste")
			(net "M_E_CPU1_SB_DQ<21>")
		)
		(pad "132" smd rect
			(at -2.050034 53.125116 90)
			(size 0.519938 1.4986)
			(layers "F.Cu" "F.Mask" "F.Paste")
			(net "GND")
		)
		(pad "133" smd rect
			(at -2.050034 53.975 90)
			(size 0.519938 1.4986)
			(layers "F.Cu" "F.Mask" "F.Paste")
			(net "M_E_CPU1_SB_DQ<24>")
		)
		(pad "134" smd rect
			(at -2.050034 54.824884 90)
			(size 0.519938 1.4986)
			(layers "F.Cu" "F.Mask" "F.Paste")
			(net "GND")
		)
		(pad "135" smd rect
			(at -2.050034 55.675022 90)
			(size 0.519938 1.4986)
			(layers "F.Cu" "F.Mask" "F.Paste")
			(net "M_E_CPU1_SB_DQ<25>")
		)
		(pad "136" smd rect
			(at -2.050034 56.524906 90)
			(size 0.519938 1.4986)
			(layers "F.Cu" "F.Mask" "F.Paste")
			(net "GND")
		)
		(pad "137" smd rect
			(at -2.050034 57.375044 90)
			(size 0.519938 1.4986)
			(layers "F.Cu" "F.Mask" "F.Paste")
			(net "M_E_CPU1_SB_DQS_DP<3>")
		)
		(pad "138" smd rect
			(at -2.050034 58.224928 90)
			(size 0.519938 1.4986)
			(layers "F.Cu" "F.Mask" "F.Paste")
			(net "M_E_CPU1_SB_DQS_DN<3>")
		)
		(pad "139" smd rect
			(at -2.050034 59.075066 90)
			(size 0.519938 1.4986)
			(layers "F.Cu" "F.Mask" "F.Paste")
			(net "GND")
		)
		(pad "140" smd rect
			(at -2.050034 59.92495 90)
			(size 0.519938 1.4986)
			(layers "F.Cu" "F.Mask" "F.Paste")
			(net "M_E_CPU1_SB_DQ<28>")
		)
		(pad "141" smd rect
			(at -2.050034 60.775088 90)
			(size 0.519938 1.4986)
			(layers "F.Cu" "F.Mask" "F.Paste")
			(net "GND")
		)
		(pad "142" smd rect
			(at -2.050034 61.624972 90)
			(size 0.519938 1.4986)
			(layers "F.Cu" "F.Mask" "F.Paste")
			(net "M_E_CPU1_SB_DQ<29>")
		)
		(pad "143" smd rect
			(at -2.050034 62.47511 90)
			(size 0.519938 1.4986)
			(layers "F.Cu" "F.Mask" "F.Paste")
			(net "GND")
		)
		(pad "144" smd rect
			(at -2.050034 63.324994 90)
			(size 0.519938 1.4986)
			(layers "F.Cu" "F.Mask" "F.Paste")
			(net "Net_2313")
		)
		(pad "145" smd rect
			(at 2.050034 -63.324994 90)
			(size 0.519938 1.4986)
			(layers "F.Cu" "F.Mask" "F.Paste")
			(net "P12V_MEM_CPU1")
		)
		(pad "146" smd rect
			(at 2.050034 -62.47511 90)
			(size 0.519938 1.4986)
			(layers "F.Cu" "F.Mask" "F.Paste")
			(net "P12V_MEM_CPU1")
		)
		(pad "147" smd rect
			(at 2.050034 -61.624972 90)
			(size 0.519938 1.4986)
			(layers "F.Cu" "F.Mask" "F.Paste")
			(net "PWRGD_CHE_CPU1_DIMM")
		)
		(pad "148" smd rect
			(at 2.050034 -60.775088 90)
			(size 0.519938 1.4986)
			(layers "F.Cu" "F.Mask" "F.Paste")
			(net "PD_CHE_CPU1_DIMM_SAA")
		)
		(pad "149" smd rect
			(at 2.050034 -59.92495 90)
			(size 0.519938 1.4986)
			(layers "F.Cu" "F.Mask" "F.Paste")
			(net "Net_2314")
		)
		(pad "150" smd rect
			(at 2.050034 -59.075066 90)
			(size 0.519938 1.4986)
			(layers "F.Cu" "F.Mask" "F.Paste")
			(net "Net_2315")
		)
		(pad "151" smd rect
			(at 2.050034 -58.224928 90)
			(size 0.519938 1.4986)
			(layers "F.Cu" "F.Mask" "F.Paste")
			(net "GND")
		)
		(pad "152" smd rect
			(at 2.050034 -57.375044 90)
			(size 0.519938 1.4986)
			(layers "F.Cu" "F.Mask" "F.Paste")
			(net "M_E_CPU1_SA_DQ<2>")
		)
		(pad "153" smd rect
			(at 2.050034 -56.524906 90)
			(size 0.519938 1.4986)
			(layers "F.Cu" "F.Mask" "F.Paste")
			(net "GND")
		)
		(pad "154" smd rect
			(at 2.050034 -55.675022 90)
			(size 0.519938 1.4986)
			(layers "F.Cu" "F.Mask" "F.Paste")
			(net "M_E_CPU1_SA_DQ<3>")
		)
		(pad "155" smd rect
			(at 2.050034 -54.824884 90)
			(size 0.519938 1.4986)
			(layers "F.Cu" "F.Mask" "F.Paste")
			(net "GND")
		)
		(pad "156" smd rect
			(at 2.050034 -53.975 90)
			(size 0.519938 1.4986)
			(layers "F.Cu" "F.Mask" "F.Paste")
			(net "M_E_CPU1_SA_DQS_DN<5>")
		)
		(pad "157" smd rect
			(at 2.050034 -53.125116 90)
			(size 0.519938 1.4986)
			(layers "F.Cu" "F.Mask" "F.Paste")
			(net "M_E_CPU1_SA_DQS_DP<5>")
		)
		(pad "158" smd rect
			(at 2.050034 -52.274978 90)
			(size 0.519938 1.4986)
			(layers "F.Cu" "F.Mask" "F.Paste")
			(net "GND")
		)
		(pad "159" smd rect
			(at 2.050034 -51.425094 90)
			(size 0.519938 1.4986)
			(layers "F.Cu" "F.Mask" "F.Paste")
			(net "M_E_CPU1_SA_DQ<6>")
		)
		(pad "160" smd rect
			(at 2.050034 -50.574956 90)
			(size 0.519938 1.4986)
			(layers "F.Cu" "F.Mask" "F.Paste")
			(net "GND")
		)
		(pad "161" smd rect
			(at 2.050034 -49.725072 90)
			(size 0.519938 1.4986)
			(layers "F.Cu" "F.Mask" "F.Paste")
			(net "M_E_CPU1_SA_DQ<7>")
		)
		(pad "162" smd rect
			(at 2.050034 -48.874934 90)
			(size 0.519938 1.4986)
			(layers "F.Cu" "F.Mask" "F.Paste")
			(net "GND")
		)
		(pad "163" smd rect
			(at 2.050034 -48.02505 90)
			(size 0.519938 1.4986)
			(layers "F.Cu" "F.Mask" "F.Paste")
			(net "M_E_CPU1_SA_DQ<10>")
		)
		(pad "164" smd rect
			(at 2.050034 -47.174912 90)
			(size 0.519938 1.4986)
			(layers "F.Cu" "F.Mask" "F.Paste")
			(net "GND")
		)
		(pad "165" smd rect
			(at 2.050034 -46.325028 90)
			(size 0.519938 1.4986)
			(layers "F.Cu" "F.Mask" "F.Paste")
			(net "M_E_CPU1_SA_DQ<11>")
		)
		(pad "166" smd rect
			(at 2.050034 -45.47489 90)
			(size 0.519938 1.4986)
			(layers "F.Cu" "F.Mask" "F.Paste")
			(net "GND")
		)
		(pad "167" smd rect
			(at 2.050034 -44.625006 90)
			(size 0.519938 1.4986)
			(layers "F.Cu" "F.Mask" "F.Paste")
			(net "M_E_CPU1_SA_DQS_DN<6>")
		)
		(pad "168" smd rect
			(at 2.050034 -43.775122 90)
			(size 0.519938 1.4986)
			(layers "F.Cu" "F.Mask" "F.Paste")
			(net "M_E_CPU1_SA_DQS_DP<6>")
		)
		(pad "169" smd rect
			(at 2.050034 -42.924984 90)
			(size 0.519938 1.4986)
			(layers "F.Cu" "F.Mask" "F.Paste")
			(net "GND")
		)
		(pad "170" smd rect
			(at 2.050034 -42.0751 90)
			(size 0.519938 1.4986)
			(layers "F.Cu" "F.Mask" "F.Paste")
			(net "M_E_CPU1_SA_DQ<14>")
		)
		(pad "171" smd rect
			(at 2.050034 -41.224962 90)
			(size 0.519938 1.4986)
			(layers "F.Cu" "F.Mask" "F.Paste")
			(net "GND")
		)
		(pad "172" smd rect
			(at 2.050034 -40.375078 90)
			(size 0.519938 1.4986)
			(layers "F.Cu" "F.Mask" "F.Paste")
			(net "M_E_CPU1_SA_DQ<15>")
		)
		(pad "173" smd rect
			(at 2.050034 -39.52494 90)
			(size 0.519938 1.4986)
			(layers "F.Cu" "F.Mask" "F.Paste")
			(net "GND")
		)
		(pad "174" smd rect
			(at 2.050034 -38.675056 90)
			(size 0.519938 1.4986)
			(layers "F.Cu" "F.Mask" "F.Paste")
			(net "M_E_CPU1_SA_DQ<18>")
		)
		(pad "175" smd rect
			(at 2.050034 -37.824918 90)
			(size 0.519938 1.4986)
			(layers "F.Cu" "F.Mask" "F.Paste")
			(net "GND")
		)
		(pad "176" smd rect
			(at 2.050034 -36.975034 90)
			(size 0.519938 1.4986)
			(layers "F.Cu" "F.Mask" "F.Paste")
			(net "M_E_CPU1_SA_DQ<19>")
		)
		(pad "177" smd rect
			(at 2.050034 -36.124896 90)
			(size 0.519938 1.4986)
			(layers "F.Cu" "F.Mask" "F.Paste")
			(net "GND")
		)
		(pad "178" smd rect
			(at 2.050034 -35.275012 90)
			(size 0.519938 1.4986)
			(layers "F.Cu" "F.Mask" "F.Paste")
			(net "M_E_CPU1_SA_DQS_DN<7>")
		)
		(pad "179" smd rect
			(at 2.050034 -34.425128 90)
			(size 0.519938 1.4986)
			(layers "F.Cu" "F.Mask" "F.Paste")
			(net "M_E_CPU1_SA_DQS_DP<7>")
		)
		(pad "180" smd rect
			(at 2.050034 -33.57499 90)
			(size 0.519938 1.4986)
			(layers "F.Cu" "F.Mask" "F.Paste")
			(net "GND")
		)
		(pad "181" smd rect
			(at 2.050034 -32.725106 90)
			(size 0.519938 1.4986)
			(layers "F.Cu" "F.Mask" "F.Paste")
			(net "M_E_CPU1_SA_DQ<22>")
		)
		(pad "182" smd rect
			(at 2.050034 -31.874968 90)
			(size 0.519938 1.4986)
			(layers "F.Cu" "F.Mask" "F.Paste")
			(net "GND")
		)
		(pad "183" smd rect
			(at 2.050034 -31.025084 90)
			(size 0.519938 1.4986)
			(layers "F.Cu" "F.Mask" "F.Paste")
			(net "M_E_CPU1_SA_DQ<23>")
		)
		(pad "184" smd rect
			(at 2.050034 -30.174946 90)
			(size 0.519938 1.4986)
			(layers "F.Cu" "F.Mask" "F.Paste")
			(net "GND")
		)
		(pad "185" smd rect
			(at 2.050034 -29.325062 90)
			(size 0.519938 1.4986)
			(layers "F.Cu" "F.Mask" "F.Paste")
			(net "M_E_CPU1_SA_DQ<26>")
		)
		(pad "186" smd rect
			(at 2.050034 -28.474924 90)
			(size 0.519938 1.4986)
			(layers "F.Cu" "F.Mask" "F.Paste")
			(net "GND")
		)
		(pad "187" smd rect
			(at 2.050034 -27.62504 90)
			(size 0.519938 1.4986)
			(layers "F.Cu" "F.Mask" "F.Paste")
			(net "M_E_CPU1_SA_DQ<27>")
		)
		(pad "188" smd rect
			(at 2.050034 -26.774902 90)
			(size 0.519938 1.4986)
			(layers "F.Cu" "F.Mask" "F.Paste")
			(net "GND")
		)
		(pad "189" smd rect
			(at 2.050034 -25.925018 90)
			(size 0.519938 1.4986)
			(layers "F.Cu" "F.Mask" "F.Paste")
			(net "M_E_CPU1_SA_DQS_DN<8>")
		)
		(pad "190" smd rect
			(at 2.050034 -25.07488 90)
			(size 0.519938 1.4986)
			(layers "F.Cu" "F.Mask" "F.Paste")
			(net "M_E_CPU1_SA_DQS_DP<8>")
		)
		(pad "191" smd rect
			(at 2.050034 -24.224996 90)
			(size 0.519938 1.4986)
			(layers "F.Cu" "F.Mask" "F.Paste")
			(net "GND")
		)
		(pad "192" smd rect
			(at 2.050034 -23.375112 90)
			(size 0.519938 1.4986)
			(layers "F.Cu" "F.Mask" "F.Paste")
			(net "M_E_CPU1_SA_DQ<30>")
		)
		(pad "193" smd rect
			(at 2.050034 -22.524974 90)
			(size 0.519938 1.4986)
			(layers "F.Cu" "F.Mask" "F.Paste")
			(net "GND")
		)
		(pad "194" smd rect
			(at 2.050034 -21.67509 90)
			(size 0.519938 1.4986)
			(layers "F.Cu" "F.Mask" "F.Paste")
			(net "M_E_CPU1_SA_DQ<31>")
		)
		(pad "195" smd rect
			(at 2.050034 -20.824952 90)
			(size 0.519938 1.4986)
			(layers "F.Cu" "F.Mask" "F.Paste")
			(net "GND")
		)
		(pad "196" smd rect
			(at 2.050034 -19.975068 90)
			(size 0.519938 1.4986)
			(layers "F.Cu" "F.Mask" "F.Paste")
			(net "M_E_CPU1_SA_CB<2>")
		)
		(pad "197" smd rect
			(at 2.050034 -19.12493 90)
			(size 0.519938 1.4986)
			(layers "F.Cu" "F.Mask" "F.Paste")
			(net "GND")
		)
		(pad "198" smd rect
			(at 2.050034 -18.275046 90)
			(size 0.519938 1.4986)
			(layers "F.Cu" "F.Mask" "F.Paste")
			(net "M_E_CPU1_SA_CB<3>")
		)
		(pad "199" smd rect
			(at 2.050034 -17.424908 90)
			(size 0.519938 1.4986)
			(layers "F.Cu" "F.Mask" "F.Paste")
			(net "GND")
		)
		(pad "200" smd rect
			(at 2.050034 -16.575024 90)
			(size 0.519938 1.4986)
			(layers "F.Cu" "F.Mask" "F.Paste")
			(net "M_E_CPU1_SA_DQS_DN<9>")
		)
		(pad "201" smd rect
			(at 2.050034 -15.724886 90)
			(size 0.519938 1.4986)
			(layers "F.Cu" "F.Mask" "F.Paste")
			(net "M_E_CPU1_SA_DQS_DP<9>")
		)
		(pad "202" smd rect
			(at 2.050034 -14.875002 90)
			(size 0.519938 1.4986)
			(layers "F.Cu" "F.Mask" "F.Paste")
			(net "GND")
		)
		(pad "203" smd rect
			(at 2.050034 -14.025118 90)
			(size 0.519938 1.4986)
			(layers "F.Cu" "F.Mask" "F.Paste")
			(net "M_E_CPU1_SA_CB<6>")
		)
		(pad "204" smd rect
			(at 2.050034 -13.17498 90)
			(size 0.519938 1.4986)
			(layers "F.Cu" "F.Mask" "F.Paste")
			(net "GND")
		)
		(pad "205" smd rect
			(at 2.050034 -12.325096 90)
			(size 0.519938 1.4986)
			(layers "F.Cu" "F.Mask" "F.Paste")
			(net "M_E_CPU1_SA_CB<7>")
		)
		(pad "206" smd rect
			(at 2.050034 -11.474958 90)
			(size 0.519938 1.4986)
			(layers "F.Cu" "F.Mask" "F.Paste")
			(net "GND")
		)
		(pad "207" smd rect
			(at 2.050034 -10.625074 90)
			(size 0.519938 1.4986)
			(layers "F.Cu" "F.Mask" "F.Paste")
			(net "M_E_CPU1_RESET_N")
		)
		(pad "208" smd rect
			(at 2.050034 -9.774936 90)
			(size 0.519938 1.4986)
			(layers "F.Cu" "F.Mask" "F.Paste")
			(net "GND")
		)
		(pad "209" smd rect
			(at 2.050034 -8.925052 90)
			(size 0.519938 1.4986)
			(layers "F.Cu" "F.Mask" "F.Paste")
			(net "M_E_CPU1_SA_CS_N<1>")
		)
		(pad "210" smd rect
			(at 2.050034 -8.074914 90)
			(size 0.519938 1.4986)
			(layers "F.Cu" "F.Mask" "F.Paste")
			(net "GND")
		)
		(pad "211" smd rect
			(at 2.050034 -7.22503 90)
			(size 0.519938 1.4986)
			(layers "F.Cu" "F.Mask" "F.Paste")
			(net "M_E_CPU1_SA_CA<1>")
		)
		(pad "212" smd rect
			(at 2.050034 -6.374892 90)
			(size 0.519938 1.4986)
			(layers "F.Cu" "F.Mask" "F.Paste")
			(net "GND")
		)
		(pad "213" smd rect
			(at 2.050034 -5.525008 90)
			(size 0.519938 1.4986)
			(layers "F.Cu" "F.Mask" "F.Paste")
			(net "M_E_CPU1_SA_CA<3>")
		)
		(pad "214" smd rect
			(at 2.050034 -4.675124 90)
			(size 0.519938 1.4986)
			(layers "F.Cu" "F.Mask" "F.Paste")
			(net "GND")
		)
		(pad "215" smd rect
			(at 2.050034 -3.824986 90)
			(size 0.519938 1.4986)
			(layers "F.Cu" "F.Mask" "F.Paste")
			(net "M_E_CPU1_SA_CA<5>")
		)
		(pad "216" smd rect
			(at 2.050034 -2.975102 90)
			(size 0.519938 1.4986)
			(layers "F.Cu" "F.Mask" "F.Paste")
			(net "GND")
		)
		(pad "217" smd rect
			(at 2.050034 -2.124964 90)
			(size 0.519938 1.4986)
			(layers "F.Cu" "F.Mask" "F.Paste")
			(net "M_E_CPU1_CLK_DP<0>")
		)
		(pad "218" smd rect
			(at 2.050034 -1.27508 90)
			(size 0.519938 1.4986)
			(layers "F.Cu" "F.Mask" "F.Paste")
			(net "M_E_CPU1_CLK_DN<0>")
		)
		(pad "219" smd rect
			(at 2.050034 -0.424942 90)
			(size 0.519938 1.4986)
			(layers "F.Cu" "F.Mask" "F.Paste")
			(net "GND")
		)
		(pad "220" smd rect
			(at 2.050034 5.525008 90)
			(size 0.519938 1.4986)
			(layers "F.Cu" "F.Mask" "F.Paste")
			(net "Net_2316")
		)
		(pad "221" smd rect
			(at 2.050034 6.374892 90)
			(size 0.519938 1.4986)
			(layers "F.Cu" "F.Mask" "F.Paste")
			(net "M_E_CPU1_SB_CA<1>")
		)
		(pad "222" smd rect
			(at 2.050034 7.22503 90)
			(size 0.519938 1.4986)
			(layers "F.Cu" "F.Mask" "F.Paste")
			(net "GND")
		)
		(pad "223" smd rect
			(at 2.050034 8.074914 90)
			(size 0.519938 1.4986)
			(layers "F.Cu" "F.Mask" "F.Paste")
			(net "M_E_CPU1_SB_CA<3>")
		)
		(pad "224" smd rect
			(at 2.050034 8.925052 90)
			(size 0.519938 1.4986)
			(layers "F.Cu" "F.Mask" "F.Paste")
			(net "GND")
		)
		(pad "225" smd rect
			(at 2.050034 9.774936 90)
			(size 0.519938 1.4986)
			(layers "F.Cu" "F.Mask" "F.Paste")
			(net "M_E_CPU1_SB_CA<5>")
		)
		(pad "226" smd rect
			(at 2.050034 10.625074 90)
			(size 0.519938 1.4986)
			(layers "F.Cu" "F.Mask" "F.Paste")
			(net "GND")
		)
	)
)
